# SCM (Grand Teton) — schematic netlist excerpt (pin names and nets, part order shuffled) for the footprints in the layout excerpt that follows; sources: Cadence DE-HDL packaged netlist, KiCad conversion of 12092022_DA0F0TMDCD0_F0T_Management_Board_D_brd_V3_OCP.brd

C137  Q_CAP  0.01UF 50V 10% X7R  pkg C0402  page 17 : A = A_BMC_ADCVREFN1 ; B = A_BMC_ADCVREFP1
R128  Q_RES  22 1% CHIP  pkg 0402LF  page 12 : A = ESPI_LPC_D0_IO0 ; B = ESPI_LPC_LAD0_IO0

(kicad_pcb
	(version 20260206)
	(generator "pcbnew")
	(generator_version "10.0")
	(general
		(thickness 1.6)
		(legacy_teardrops no)
	)
	(paper "A4")
	(title_block
		(title "12092022_DA0F0TMDCD0_F0T_Management_Board_D_brd_V3_OCP.brd")
		(comment 1 "Grand Teton / footprints 1378-1379 of 1440")
	)
	(layers
		(0 "F.Cu" signal "TOP")
		(4 "In1.Cu" signal "GND")
		(6 "In2.Cu" signal "IN1")
		(8 "In3.Cu" signal "GND1")
		(10 "In4.Cu" signal "IN2")
		(12 "In5.Cu" signal "VCC")
		(14 "In6.Cu" signal "VCC1")
		(16 "In7.Cu" signal "IN3")
		(18 "In8.Cu" signal "GND2")
		(20 "In9.Cu" signal "IN4")
		(22 "In10.Cu" signal "GND3")
		(2 "B.Cu" signal "BOTTOM")
		(9 "F.Adhes" user "F.Adhesive")
		(11 "B.Adhes" user "B.Adhesive")
		(13 "F.Paste" user "Package Geometry/Pastemask Top")
		(15 "B.Paste" user "Package Geometry/Pastemask Bottom")
		(5 "F.SilkS" user "Ref Des/Silkscreen Top")
		(7 "B.SilkS" user "Ref Des/Silkscreen Bottom")
		(1 "F.Mask" user "Board Geometry/Soldermask Top")
		(3 "B.Mask" user "Board Geometry/Soldermask Bottom")
		(17 "Dwgs.User" user "User.Drawings")
		(19 "Cmts.User" user "User.Comments")
		(21 "Eco1.User" user "User.Eco1")
		(23 "Eco2.User" user "User.Eco2")
		(25 "Edge.Cuts" user "Board Geometry/Outline")
		(27 "Margin" user)
		(31 "F.CrtYd" user "Package Geometry/Place Bound Top")
		(29 "B.CrtYd" user "Package Geometry/Place Bound Bottom")
		(35 "F.Fab" user "Ref Des/Assembly Top")
		(33 "B.Fab" user "Ref Des/Assembly Bottom")
	)
	(footprint ""
		(layer "B.Cu")
		(at 64.634364 -62.037722 -90)
		(property "Reference" "R128"
			(at 0 0 90)
			(layer "B.SilkS")
			(hide yes)
			(effects
				(font
					(size 1.27 1.27)
				)
				(justify mirror)
			)
		)
		(property "Value" ""
			(at 0 0 90)
			(layer "B.Fab")
			(effects
				(font
					(size 1.27 1.27)
				)
				(justify mirror)
			)
		)
		(duplicate_pad_numbers_are_jumpers no)
		(fp_line
			(start -0.7874 0.4064)
			(end 0.7874 0.4064)
			(stroke
				(width 0.1524)
				(type default)
			)
			(layer "B.SilkS")
		)
		(fp_line
			(start 0.7874 0.4064)
			(end 0.7874 -0.4064)
			(stroke
				(width 0.1524)
				(type default)
			)
			(layer "B.SilkS")
		)
		(fp_line
			(start -0.7874 -0.4064)
			(end -0.7874 0.4064)
			(stroke
				(width 0.1524)
				(type default)
			)
			(layer "B.SilkS")
		)
		(fp_line
			(start 0.7874 -0.4064)
			(end -0.7874 -0.4064)
			(stroke
				(width 0.1524)
				(type default)
			)
			(layer "B.SilkS")
		)
		(fp_line
			(start -0.67945 0.3048)
			(end -0.120396 0.3048)
			(stroke
				(width 0.1)
				(type default)
			)
			(layer "B.Fab")
		)
		(fp_line
			(start -0.120396 0.3048)
			(end -0.120396 0.2794)
			(stroke
				(width 0.1)
				(type default)
			)
			(layer "B.Fab")
		)
		(fp_line
			(start 0.12065 0.3048)
			(end 0.67945 0.3048)
			(stroke
				(width 0.1)
				(type default)
			)
			(layer "B.Fab")
		)
		(fp_line
			(start 0.67945 0.3048)
			(end 0.67945 -0.305054)
			(stroke
				(width 0.1)
				(type default)
			)
			(layer "B.Fab")
		)
		(fp_line
			(start -0.120396 0.2794)
			(end 0.12065 0.2794)
			(stroke
				(width 0.1)
				(type default)
			)
			(layer "B.Fab")
		)
		(fp_line
			(start 0.12065 0.2794)
			(end 0.12065 0.3048)
			(stroke
				(width 0.1)
				(type default)
			)
			(layer "B.Fab")
		)
		(fp_line
			(start -0.12065 -0.2794)
			(end -0.12065 -0.3048)
			(stroke
				(width 0.1)
				(type default)
			)
			(layer "B.Fab")
		)
		(fp_line
			(start 0.12065 -0.2794)
			(end -0.12065 -0.2794)
			(stroke
				(width 0.1)
				(type default)
			)
			(layer "B.Fab")
		)
		(fp_line
			(start -0.67945 -0.3048)
			(end -0.67945 0.3048)
			(stroke
				(width 0.1)
				(type default)
			)
			(layer "B.Fab")
		)
		(fp_line
			(start -0.12065 -0.3048)
			(end -0.67945 -0.3048)
			(stroke
				(width 0.1)
				(type default)
			)
			(layer "B.Fab")
		)
		(fp_line
			(start 0.12065 -0.305054)
			(end 0.12065 -0.2794)
			(stroke
				(width 0.1)
				(type default)
			)
			(layer "B.Fab")
		)
		(fp_line
			(start 0.67945 -0.305054)
			(end 0.12065 -0.305054)
			(stroke
				(width 0.1)
				(type default)
			)
			(layer "B.Fab")
		)
		(pad "1" smd circle
			(at 0.40005 0 90)
			(size 0 0)
			(layers "B.Cu" "B.Mask" "B.Paste")
			(net "ESPI_LPC_D0_IO0")
		)
		(pad "2" smd circle
			(at -0.40005 0 90)
			(size 0 0)
			(layers "B.Cu" "B.Mask" "B.Paste")
			(net "ESPI_LPC_LAD0_IO0")
		)
	)
	(footprint ""
		(layer "B.Cu")
		(at 50.905156 -60.26277 180)
		(property "Reference" "C137"
			(at 0 0 0)
			(layer "B.SilkS")
			(hide yes)
			(effects
				(font
					(size 1.27 1.27)
				)
				(justify mirror)
			)
		)
		(property "Value" ""
			(at 0 0 0)
			(layer "B.Fab")
			(effects
				(font
					(size 1.27 1.27)
				)
				(justify mirror)
			)
		)
		(duplicate_pad_numbers_are_jumpers no)
		(fp_line
			(start 0.7874 0.4064)
			(end 0.7874 -0.4064)
			(stroke
				(width 0.1524)
				(type default)
			)
			(layer "B.SilkS")
		)
		(fp_line
			(start 0.7874 -0.4064)
			(end -0.7874 -0.4064)
			(stroke
				(width 0.1524)
				(type default)
			)
			(layer "B.SilkS")
		)
		(fp_line
			(start -0.7874 0.4064)
			(end 0.7874 0.4064)
			(stroke
				(width 0.1524)
				(type default)
			)
			(layer "B.SilkS")
		)
		(fp_line
			(start -0.7874 -0.4064)
			(end -0.7874 0.4064)
			(stroke
				(width 0.1524)
				(type default)
			)
			(layer "B.SilkS")
		)
		(fp_line
			(start 0.67945 0.3048)
			(end 0.67945 -0.305054)
			(stroke
				(width 0.1)
				(type default)
			)
			(layer "B.Fab")
		)
		(fp_line
			(start 0.67945 -0.305054)
			(end 0.12065 -0.305054)
			(stroke
				(width 0.1)
				(type default)
			)
			(layer "B.Fab")
		)
		(fp_line
			(start 0.12065 0.3048)
			(end 0.67945 0.3048)
			(stroke
				(width 0.1)
				(type default)
			)
			(layer "B.Fab")
		)
		(fp_line
			(start 0.12065 0.2794)
			(end 0.12065 0.3048)
			(stroke
				(width 0.1)
				(type default)
			)
			(layer "B.Fab")
		)
		(fp_line
			(start 0.12065 -0.2794)
			(end -0.12065 -0.2794)
			(stroke
				(width 0.1)
				(type default)
			)
			(layer "B.Fab")
		)
		(fp_line
			(start 0.12065 -0.305054)
			(end 0.12065 -0.2794)
			(stroke
				(width 0.1)
				(type default)
			)
			(layer "B.Fab")
		)
		(fp_line
			(start -0.120396 0.3048)
			(end -0.120396 0.2794)
			(stroke
				(width 0.1)
				(type default)
			)
			(layer "B.Fab")
		)
		(fp_line
			(start -0.120396 0.2794)
			(end 0.12065 0.2794)
			(stroke
				(width 0.1)
				(type default)
			)
			(layer "B.Fab")
		)
		(fp_line
			(start -0.12065 -0.2794)
			(end -0.12065 -0.3048)
			(stroke
				(width 0.1)
				(type default)
			)
			(layer "B.Fab")
		)
		(fp_line
			(start -0.12065 -0.3048)
			(end -0.67945 -0.3048)
			(stroke
				(width 0.1)
				(type default)
			)
			(layer "B.Fab")
		)
		(fp_line
			(start -0.67945 0.3048)
			(end -0.120396 0.3048)
			(stroke
				(width 0.1)
				(type default)
			)
			(layer "B.Fab")
		)
		(fp_line
			(start -0.67945 -0.3048)
			(end -0.67945 0.3048)
			(stroke
				(width 0.1)
				(type default)
			)
			(layer "B.Fab")
		)
		(pad "1" smd circle
			(at 0.40005 0)
			(size 0 0)
			(layers "B.Cu" "B.Mask" "B.Paste")
			(net "A_BMC_ADCVREFN1")
		)
		(pad "2" smd circle
			(at -0.40005 0)
			(size 0 0)
			(layers "B.Cu" "B.Mask" "B.Paste")
			(net "A_BMC_ADCVREFP1")
		)
	)
)
